# T6G (Grand Teton) — schematic netlist excerpt (pin names and nets, part order shuffled) for the footprints in the layout excerpt that follows; sources: Cadence DE-HDL packaged netlist, KiCad conversion of 04192023_DAF0TMB3IC0_F0TG_MB_C_brd_V02_OCP.brd

U24  MOSFET_N  BSS138K IC  pkg SMLF  page 136
  DRAIN  = HP_LVC3_OCP_SFF_PRSNT2
  GATE  = HP_LVC3_OCP_SFF_PRSNT2_N
  SOURCE  = GND

C1567  Q_CAP  1UF 25V 10% X6S  pkg C0402  page 187 : A = P1V5_BAT ; B = GND
C951  Q_CAP_DIFFBUS  DIFF BUS_0.22UF 6.3V 20% X6S  pkg C0201  page 63 : \1\ = P5E_CPU0_P1_TX_C_DP<7> ; \2\ = P5E_CPU0_P1_TX_DP<7>

(kicad_pcb
	(version 20260206)
	(generator "pcbnew")
	(generator_version "10.0")
	(general
		(thickness 1.6)
		(legacy_teardrops no)
	)
	(paper "A4")
	(title_block
		(title "04192023_DAF0TMB3IC0_F0TG_MB_C_brd_V02_OCP.brd")
		(comment 1 "Grand Teton / footprints 1714-1716 of 8354")
	)
	(layers
		(0 "F.Cu" signal "TOP")
		(4 "In1.Cu" signal "GND")
		(6 "In2.Cu" signal "IN1")
		(8 "In3.Cu" signal "GND1")
		(10 "In4.Cu" signal "IN2")
		(12 "In5.Cu" signal "GND2")
		(14 "In6.Cu" signal "IN3")
		(16 "In7.Cu" signal "GND3")
		(18 "In8.Cu" signal "VCC")
		(20 "In9.Cu" signal "VCC1")
		(22 "In10.Cu" signal "GND4")
		(24 "In11.Cu" signal "IN4")
		(26 "In12.Cu" signal "GND5")
		(28 "In13.Cu" signal "IN5")
		(30 "In14.Cu" signal "GND6")
		(32 "In15.Cu" signal "IN6")
		(34 "In16.Cu" signal "GND7")
		(2 "B.Cu" signal "BOTTOM")
		(9 "F.Adhes" user "F.Adhesive")
		(11 "B.Adhes" user "B.Adhesive")
		(13 "F.Paste" user "Package Geometry/Pastemask Top")
		(15 "B.Paste" user "Package Geometry/Pastemask Bottom")
		(5 "F.SilkS" user "Ref Des/Silkscreen Top")
		(7 "B.SilkS" user "Ref Des/Silkscreen Bottom")
		(1 "F.Mask" user "Board Geometry/Soldermask Top")
		(3 "B.Mask" user "Board Geometry/Soldermask Bottom")
		(17 "Dwgs.User" user "User.Drawings")
		(19 "Cmts.User" user "User.Comments")
		(21 "Eco1.User" user "User.Eco1")
		(23 "Eco2.User" user "User.Eco2")
		(25 "Edge.Cuts" user "Board Geometry/Outline")
		(27 "Margin" user)
		(31 "F.CrtYd" user "Package Geometry/Place Bound Top")
		(29 "B.CrtYd" user "Package Geometry/Place Bound Bottom")
		(35 "F.Fab" user "Ref Des/Assembly Top")
		(33 "B.Fab" user "Ref Des/Assembly Bottom")
	)
	(footprint ""
		(layer "F.Cu")
		(at 332.195678 -27.267662 90)
		(property "Reference" "C1567"
			(at 0 0 90)
			(layer "F.SilkS")
			(hide yes)
			(effects
				(font
					(size 1.27 1.27)
				)
			)
		)
		(property "Value" ""
			(at 0 0 90)
			(layer "F.Fab")
			(effects
				(font
					(size 1.27 1.27)
				)
			)
		)
		(duplicate_pad_numbers_are_jumpers no)
		(fp_line
			(start 0.7874 -0.4064)
			(end 0.7874 0.4064)
			(stroke
				(width 0.1524)
				(type default)
			)
			(layer "F.SilkS")
		)
		(fp_line
			(start -0.7874 -0.4064)
			(end 0.7874 -0.4064)
			(stroke
				(width 0.1524)
				(type default)
			)
			(layer "F.SilkS")
		)
		(fp_line
			(start 0.7874 0.4064)
			(end -0.7874 0.4064)
			(stroke
				(width 0.1524)
				(type default)
			)
			(layer "F.SilkS")
		)
		(fp_line
			(start -0.7874 0.4064)
			(end -0.7874 -0.4064)
			(stroke
				(width 0.1524)
				(type default)
			)
			(layer "F.SilkS")
		)
		(fp_line
			(start -0.12065 -0.305054)
			(end -0.12065 -0.2794)
			(stroke
				(width 0.1)
				(type default)
			)
			(layer "F.Fab")
		)
		(fp_line
			(start -0.67945 -0.305054)
			(end -0.12065 -0.305054)
			(stroke
				(width 0.1)
				(type default)
			)
			(layer "F.Fab")
		)
		(fp_line
			(start 0.67945 -0.3048)
			(end 0.67945 0.3048)
			(stroke
				(width 0.1)
				(type default)
			)
			(layer "F.Fab")
		)
		(fp_line
			(start 0.12065 -0.3048)
			(end 0.67945 -0.3048)
			(stroke
				(width 0.1)
				(type default)
			)
			(layer "F.Fab")
		)
		(fp_line
			(start 0.12065 -0.2794)
			(end 0.12065 -0.3048)
			(stroke
				(width 0.1)
				(type default)
			)
			(layer "F.Fab")
		)
		(fp_line
			(start -0.12065 -0.2794)
			(end 0.12065 -0.2794)
			(stroke
				(width 0.1)
				(type default)
			)
			(layer "F.Fab")
		)
		(fp_line
			(start 0.120396 0.2794)
			(end -0.12065 0.2794)
			(stroke
				(width 0.1)
				(type default)
			)
			(layer "F.Fab")
		)
		(fp_line
			(start -0.12065 0.2794)
			(end -0.12065 0.3048)
			(stroke
				(width 0.1)
				(type default)
			)
			(layer "F.Fab")
		)
		(fp_line
			(start 0.67945 0.3048)
			(end 0.120396 0.3048)
			(stroke
				(width 0.1)
				(type default)
			)
			(layer "F.Fab")
		)
		(fp_line
			(start 0.120396 0.3048)
			(end 0.120396 0.2794)
			(stroke
				(width 0.1)
				(type default)
			)
			(layer "F.Fab")
		)
		(fp_line
			(start -0.12065 0.3048)
			(end -0.67945 0.3048)
			(stroke
				(width 0.1)
				(type default)
			)
			(layer "F.Fab")
		)
		(fp_line
			(start -0.67945 0.3048)
			(end -0.67945 -0.305054)
			(stroke
				(width 0.1)
				(type default)
			)
			(layer "F.Fab")
		)
		(pad "1" smd circle
			(at -0.40005 0 90)
			(size 0 0)
			(layers "F.Cu" "F.Mask" "F.Paste")
			(net "P1V5_BAT")
		)
		(pad "2" smd circle
			(at 0.40005 0 90)
			(size 0 0)
			(layers "F.Cu" "F.Mask" "F.Paste")
			(net "GND")
		)
	)
	(footprint ""
		(layer "F.Cu")
		(at 155.575 -114.554)
		(property "Reference" "U24"
			(at -3.103372 -0.603504 0)
			(unlocked yes)
			(layer "F.SilkS")
			(effects
				(font
					(size 0.7874 0.5842)
					(thickness 0.1524)
				)
			)
		)
		(property "Value" ""
			(at 0 0 0)
			(layer "F.Fab")
			(effects
				(font
					(size 1.27 1.27)
				)
			)
		)
		(duplicate_pad_numbers_are_jumpers no)
		(fp_line
			(start -1.949958 -1.610106)
			(end 1.949958 -1.610106)
			(stroke
				(width 0.1524)
				(type default)
			)
			(layer "F.SilkS")
		)
		(fp_line
			(start -1.949958 1.610106)
			(end -1.949958 -1.610106)
			(stroke
				(width 0.1524)
				(type default)
			)
			(layer "F.SilkS")
		)
		(fp_line
			(start 1.949958 -1.560068)
			(end 1.949958 1.610106)
			(stroke
				(width 0.1524)
				(type default)
			)
			(layer "F.SilkS")
		)
		(fp_line
			(start 1.949958 1.610106)
			(end -1.949958 1.610106)
			(stroke
				(width 0.1524)
				(type default)
			)
			(layer "F.SilkS")
		)
		(fp_line
			(start -0.750062 -1.560068)
			(end 0.750062 -1.560068)
			(stroke
				(width 0.1)
				(type default)
			)
			(layer "F.Fab")
		)
		(fp_line
			(start -0.750062 1.560068)
			(end -0.750062 -1.560068)
			(stroke
				(width 0.1)
				(type default)
			)
			(layer "F.Fab")
		)
		(fp_line
			(start 0.750062 -1.560068)
			(end 0.750062 1.560068)
			(stroke
				(width 0.1)
				(type default)
			)
			(layer "F.Fab")
		)
		(fp_line
			(start 0.750062 1.560068)
			(end -0.750062 1.560068)
			(stroke
				(width 0.1)
				(type default)
			)
			(layer "F.Fab")
		)
		(pad "D" smd rect
			(at 1.100074 0 270)
			(size 1.016 1.4224)
			(layers "F.Cu" "F.Mask" "F.Paste")
			(net "HP_LVC3_OCP_SFF_PRSNT2")
		)
		(pad "G" smd rect
			(at -1.100074 -0.94996 270)
			(size 1.016 1.4224)
			(layers "F.Cu" "F.Mask" "F.Paste")
			(net "HP_LVC3_OCP_SFF_PRSNT2_N")
		)
		(pad "S" smd rect
			(at -1.100074 0.94996 270)
			(size 1.016 1.4224)
			(layers "F.Cu" "F.Mask" "F.Paste")
			(net "GND")
		)
	)
	(footprint ""
		(layer "F.Cu")
		(at 343.429844 -383.88163 -90)
		(property "Reference" "C951"
			(at 0 0 270)
			(layer "F.SilkS")
			(hide yes)
			(effects
				(font
					(size 1.27 1.27)
				)
			)
		)
		(property "Value" ""
			(at 0 0 270)
			(layer "F.Fab")
			(effects
				(font
					(size 1.27 1.27)
				)
			)
		)
		(duplicate_pad_numbers_are_jumpers no)
		(fp_line
			(start -0.299974 0.150114)
			(end -0.299974 -0.150114)
			(stroke
				(width 0.1)
				(type default)
			)
			(layer "F.Fab")
		)
		(fp_line
			(start 0.299974 0.150114)
			(end -0.299974 0.150114)
			(stroke
				(width 0.1)
				(type default)
			)
			(layer "F.Fab")
		)
		(fp_line
			(start -0.299974 -0.150114)
			(end 0.299974 -0.150114)
			(stroke
				(width 0.1)
				(type default)
			)
			(layer "F.Fab")
		)
		(fp_line
			(start 0.299974 -0.150114)
			(end 0.299974 0.150114)
			(stroke
				(width 0.1)
				(type default)
			)
			(layer "F.Fab")
		)
		(pad "1" smd rect
			(at -0.2667 0 270)
			(size 0.3048 0.381)
			(layers "F.Cu" "F.Mask" "F.Paste")
			(net "P5E_CPU0_P1_TX_C_DP<7>")
		)
		(pad "2" smd rect
			(at 0.2667 0 270)
			(size 0.3048 0.381)
			(layers "F.Cu" "F.Mask" "F.Paste")
			(net "P5E_CPU0_P1_TX_DP<7>")
		)
	)
)
